(kicad_pcb
	(version 20260206)
	(generator "pcbnew")
	(generator_version "10.0")
	(general
		(thickness 1.6)
		(legacy_teardrops no)
	)
	(paper "A4")
	(title_block
		(title "04192023_DAF0TMB3IC0_F0TG_MB_C_brd_V02_OCP.brd")
		(comment 1 "Grand Teton / footprints 5986-5992 of 8354")
	)
	(layers
		(0 "F.Cu" signal "TOP")
		(4 "In1.Cu" signal "GND")
		(6 "In2.Cu" signal "IN1")
		(8 "In3.Cu" signal "GND1")
		(10 "In4.Cu" signal "IN2")
		(12 "In5.Cu" signal "GND2")
		(14 "In6.Cu" signal "IN3")
		(16 "In7.Cu" signal "GND3")
		(18 "In8.Cu" signal "VCC")
		(20 "In9.Cu" signal "VCC1")
		(22 "In10.Cu" signal "GND4")
		(24 "In11.Cu" signal "IN4")
		(26 "In12.Cu" signal "GND5")
		(28 "In13.Cu" signal "IN5")
		(30 "In14.Cu" signal "GND6")
		(32 "In15.Cu" signal "IN6")
		(34 "In16.Cu" signal "GND7")
		(2 "B.Cu" signal "BOTTOM")
		(9 "F.Adhes" user "F.Adhesive")
		(11 "B.Adhes" user "B.Adhesive")
		(13 "F.Paste" user "Package Geometry/Pastemask Top")
		(15 "B.Paste" user "Package Geometry/Pastemask Bottom")
		(5 "F.SilkS" user "Ref Des/Silkscreen Top")
		(7 "B.SilkS" user "Ref Des/Silkscreen Bottom")
		(1 "F.Mask" user "Board Geometry/Soldermask Top")
		(3 "B.Mask" user "Board Geometry/Soldermask Bottom")
		(17 "Dwgs.User" user "User.Drawings")
		(19 "Cmts.User" user "User.Comments")
		(21 "Eco1.User" user "User.Eco1")
		(23 "Eco2.User" user "User.Eco2")
		(25 "Edge.Cuts" user "Board Geometry/Outline")
		(27 "Margin" user)
		(31 "F.CrtYd" user "Package Geometry/Place Bound Top")
		(29 "B.CrtYd" user "Package Geometry/Place Bound Bottom")
		(35 "F.Fab" user "Ref Des/Assembly Top")
		(33 "B.Fab" user "Ref Des/Assembly Bottom")
	)
	(footprint ""
		(layer "B.Cu")
		(at 181.534562 -97.123504 -90)
		(property "Reference" "R489"
			(at 0 0 90)
			(layer "B.SilkS")
			(hide yes)
			(effects
				(font
					(size 1.27 1.27)
				)
				(justify mirror)
			)
		)
		(property "Value" ""
			(at 0 0 90)
			(layer "B.Fab")
			(effects
				(font
					(size 1.27 1.27)
				)
				(justify mirror)
			)
		)
		(duplicate_pad_numbers_are_jumpers no)
		(fp_line
			(start -0.7874 0.4064)
			(end 0.7874 0.4064)
			(stroke
				(width 0.1524)
				(type default)
			)
			(layer "B.SilkS")
		)
		(fp_line
			(start 0.7874 0.4064)
			(end 0.7874 -0.4064)
			(stroke
				(width 0.1524)
				(type default)
			)
			(layer "B.SilkS")
		)
		(fp_line
			(start -0.7874 -0.4064)
			(end -0.7874 0.4064)
			(stroke
				(width 0.1524)
				(type default)
			)
			(layer "B.SilkS")
		)
		(fp_line
			(start 0.7874 -0.4064)
			(end -0.7874 -0.4064)
			(stroke
				(width 0.1524)
				(type default)
			)
			(layer "B.SilkS")
		)
		(fp_line
			(start -0.67945 0.3048)
			(end -0.120396 0.3048)
			(stroke
				(width 0.1)
				(type default)
			)
			(layer "B.Fab")
		)
		(fp_line
			(start -0.120396 0.3048)
			(end -0.120396 0.2794)
			(stroke
				(width 0.1)
				(type default)
			)
			(layer "B.Fab")
		)
		(fp_line
			(start 0.12065 0.3048)
			(end 0.67945 0.3048)
			(stroke
				(width 0.1)
				(type default)
			)
			(layer "B.Fab")
		)
		(fp_line
			(start 0.67945 0.3048)
			(end 0.67945 -0.305054)
			(stroke
				(width 0.1)
				(type default)
			)
			(layer "B.Fab")
		)
		(fp_line
			(start -0.120396 0.2794)
			(end 0.12065 0.2794)
			(stroke
				(width 0.1)
				(type default)
			)
			(layer "B.Fab")
		)
		(fp_line
			(start 0.12065 0.2794)
			(end 0.12065 0.3048)
			(stroke
				(width 0.1)
				(type default)
			)
			(layer "B.Fab")
		)
		(fp_line
			(start -0.12065 -0.2794)
			(end -0.12065 -0.3048)
			(stroke
				(width 0.1)
				(type default)
			)
			(layer "B.Fab")
		)
		(fp_line
			(start 0.12065 -0.2794)
			(end -0.12065 -0.2794)
			(stroke
				(width 0.1)
				(type default)
			)
			(layer "B.Fab")
		)
		(fp_line
			(start -0.67945 -0.3048)
			(end -0.67945 0.3048)
			(stroke
				(width 0.1)
				(type default)
			)
			(layer "B.Fab")
		)
		(fp_line
			(start -0.12065 -0.3048)
			(end -0.67945 -0.3048)
			(stroke
				(width 0.1)
				(type default)
			)
			(layer "B.Fab")
		)
		(fp_line
			(start 0.12065 -0.305054)
			(end 0.12065 -0.2794)
			(stroke
				(width 0.1)
				(type default)
			)
			(layer "B.Fab")
		)
		(fp_line
			(start 0.67945 -0.305054)
			(end 0.12065 -0.305054)
			(stroke
				(width 0.1)
				(type default)
			)
			(layer "B.Fab")
		)
		(pad "1" smd circle
			(at 0.40005 0 90)
			(size 0 0)
			(layers "B.Cu" "B.Mask" "B.Paste")
			(net "CPU0_THERMTRIP_N")
		)
		(pad "2" smd circle
			(at -0.40005 0 90)
			(size 0 0)
			(layers "B.Cu" "B.Mask" "B.Paste")
			(net "CPU0_THERMTRIP_R_N")
		)
	)
	(footprint ""
		(layer "B.Cu")
		(at 89.518998 -390.560052 90)
		(property "Reference" "C199"
			(at 0 0 90)
			(layer "B.SilkS")
			(hide yes)
			(effects
				(font
					(size 1.27 1.27)
				)
				(justify mirror)
			)
		)
		(property "Value" ""
			(at 0 0 90)
			(layer "B.Fab")
			(effects
				(font
					(size 1.27 1.27)
				)
				(justify mirror)
			)
		)
		(duplicate_pad_numbers_are_jumpers no)
		(fp_line
			(start 0.7874 -0.4064)
			(end -0.7874 -0.4064)
			(stroke
				(width 0.1524)
				(type default)
			)
			(layer "B.SilkS")
		)
		(fp_line
			(start -0.7874 -0.4064)
			(end -0.7874 0.4064)
			(stroke
				(width 0.1524)
				(type default)
			)
			(layer "B.SilkS")
		)
		(fp_line
			(start 0.7874 0.4064)
			(end 0.7874 -0.4064)
			(stroke
				(width 0.1524)
				(type default)
			)
			(layer "B.SilkS")
		)
		(fp_line
			(start -0.7874 0.4064)
			(end 0.7874 0.4064)
			(stroke
				(width 0.1524)
				(type default)
			)
			(layer "B.SilkS")
		)
		(fp_line
			(start 0.67945 -0.305054)
			(end 0.12065 -0.305054)
			(stroke
				(width 0.1)
				(type default)
			)
			(layer "B.Fab")
		)
		(fp_line
			(start 0.12065 -0.305054)
			(end 0.12065 -0.2794)
			(stroke
				(width 0.1)
				(type default)
			)
			(layer "B.Fab")
		)
		(fp_line
			(start -0.12065 -0.3048)
			(end -0.67945 -0.3048)
			(stroke
				(width 0.1)
				(type default)
			)
			(layer "B.Fab")
		)
		(fp_line
			(start -0.67945 -0.3048)
			(end -0.67945 0.3048)
			(stroke
				(width 0.1)
				(type default)
			)
			(layer "B.Fab")
		)
		(fp_line
			(start 0.12065 -0.2794)
			(end -0.12065 -0.2794)
			(stroke
				(width 0.1)
				(type default)
			)
			(layer "B.Fab")
		)
		(fp_line
			(start -0.12065 -0.2794)
			(end -0.12065 -0.3048)
			(stroke
				(width 0.1)
				(type default)
			)
			(layer "B.Fab")
		)
		(fp_line
			(start 0.12065 0.2794)
			(end 0.12065 0.3048)
			(stroke
				(width 0.1)
				(type default)
			)
			(layer "B.Fab")
		)
		(fp_line
			(start -0.120396 0.2794)
			(end 0.12065 0.2794)
			(stroke
				(width 0.1)
				(type default)
			)
			(layer "B.Fab")
		)
		(fp_line
			(start 0.67945 0.3048)
			(end 0.67945 -0.305054)
			(stroke
				(width 0.1)
				(type default)
			)
			(layer "B.Fab")
		)
		(fp_line
			(start 0.12065 0.3048)
			(end 0.67945 0.3048)
			(stroke
				(width 0.1)
				(type default)
			)
			(layer "B.Fab")
		)
		(fp_line
			(start -0.120396 0.3048)
			(end -0.120396 0.2794)
			(stroke
				(width 0.1)
				(type default)
			)
			(layer "B.Fab")
		)
		(fp_line
			(start -0.67945 0.3048)
			(end -0.120396 0.3048)
			(stroke
				(width 0.1)
				(type default)
			)
			(layer "B.Fab")
		)
		(pad "1" smd circle
			(at 0.40005 0 270)
			(size 0 0)
			(layers "B.Cu" "B.Mask" "B.Paste")
			(net "P1V8_CPU1_RT1_1A")
		)
		(pad "2" smd circle
			(at -0.40005 0 270)
			(size 0 0)
			(layers "B.Cu" "B.Mask" "B.Paste")
			(net "GND")
		)
	)
	(footprint ""
		(layer "B.Cu")
		(at 102.389432 -390.073134 180)
		(property "Reference" "C317"
			(at 0 0 0)
			(layer "B.SilkS")
			(hide yes)
			(effects
				(font
					(size 1.27 1.27)
				)
				(justify mirror)
			)
		)
		(property "Value" ""
			(at 0 0 0)
			(layer "B.Fab")
			(effects
				(font
					(size 1.27 1.27)
				)
				(justify mirror)
			)
		)
		(duplicate_pad_numbers_are_jumpers no)
		(fp_line
			(start 1.524 0.762)
			(end 1.524 -0.762)
			(stroke
				(width 0.1524)
				(type default)
			)
			(layer "B.SilkS")
		)
		(fp_line
			(start 1.524 -0.762)
			(end -1.524 -0.762)
			(stroke
				(width 0.1524)
				(type default)
			)
			(layer "B.SilkS")
		)
		(fp_line
			(start -1.524 0.762)
			(end 1.524 0.762)
			(stroke
				(width 0.1524)
				(type default)
			)
			(layer "B.SilkS")
		)
		(fp_line
			(start -1.524 -0.762)
			(end -1.524 0.762)
			(stroke
				(width 0.1524)
				(type default)
			)
			(layer "B.SilkS")
		)
		(fp_line
			(start 1.1049 0.724916)
			(end -1.1049 0.724916)
			(stroke
				(width 0.1)
				(type default)
			)
			(layer "B.Fab")
		)
		(fp_line
			(start 1.1049 -0.724916)
			(end 1.1049 0.724916)
			(stroke
				(width 0.1)
				(type default)
			)
			(layer "B.Fab")
		)
		(fp_line
			(start -1.1049 0.724916)
			(end -1.1049 -0.724916)
			(stroke
				(width 0.1)
				(type default)
			)
			(layer "B.Fab")
		)
		(fp_line
			(start -1.1049 -0.724916)
			(end 1.1049 -0.724916)
			(stroke
				(width 0.1)
				(type default)
			)
			(layer "B.Fab")
		)
		(pad "1" smd rect
			(at 0.889 0 180)
			(size 1.016 1.27)
			(layers "B.Cu" "B.Mask" "B.Paste")
			(net "P0V9_CPU1_RT1_2A")
		)
		(pad "2" smd rect
			(at -0.889 0 180)
			(size 1.016 1.27)
			(layers "B.Cu" "B.Mask" "B.Paste")
			(net "GND")
		)
	)
	(footprint ""
		(layer "B.Cu")
		(at 168.367202 -14.4653 -90)
		(property "Reference" "R1386"
			(at 0 0 90)
			(layer "B.SilkS")
			(hide yes)
			(effects
				(font
					(size 1.27 1.27)
				)
				(justify mirror)
			)
		)
		(property "Value" ""
			(at 0 0 90)
			(layer "B.Fab")
			(effects
				(font
					(size 1.27 1.27)
				)
				(justify mirror)
			)
		)
		(duplicate_pad_numbers_are_jumpers no)
		(fp_line
			(start -0.7874 0.4064)
			(end 0.7874 0.4064)
			(stroke
				(width 0.1524)
				(type default)
			)
			(layer "B.SilkS")
		)
		(fp_line
			(start 0.7874 0.4064)
			(end 0.7874 -0.4064)
			(stroke
				(width 0.1524)
				(type default)
			)
			(layer "B.SilkS")
		)
		(fp_line
			(start -0.7874 -0.4064)
			(end -0.7874 0.4064)
			(stroke
				(width 0.1524)
				(type default)
			)
			(layer "B.SilkS")
		)
		(fp_line
			(start 0.7874 -0.4064)
			(end -0.7874 -0.4064)
			(stroke
				(width 0.1524)
				(type default)
			)
			(layer "B.SilkS")
		)
		(fp_line
			(start -0.67945 0.3048)
			(end -0.120396 0.3048)
			(stroke
				(width 0.1)
				(type default)
			)
			(layer "B.Fab")
		)
		(fp_line
			(start -0.120396 0.3048)
			(end -0.120396 0.2794)
			(stroke
				(width 0.1)
				(type default)
			)
			(layer "B.Fab")
		)
		(fp_line
			(start 0.12065 0.3048)
			(end 0.67945 0.3048)
			(stroke
				(width 0.1)
				(type default)
			)
			(layer "B.Fab")
		)
		(fp_line
			(start 0.67945 0.3048)
			(end 0.67945 -0.305054)
			(stroke
				(width 0.1)
				(type default)
			)
			(layer "B.Fab")
		)
		(fp_line
			(start -0.120396 0.2794)
			(end 0.12065 0.2794)
			(stroke
				(width 0.1)
				(type default)
			)
			(layer "B.Fab")
		)
		(fp_line
			(start 0.12065 0.2794)
			(end 0.12065 0.3048)
			(stroke
				(width 0.1)
				(type default)
			)
			(layer "B.Fab")
		)
		(fp_line
			(start -0.12065 -0.2794)
			(end -0.12065 -0.3048)
			(stroke
				(width 0.1)
				(type default)
			)
			(layer "B.Fab")
		)
		(fp_line
			(start 0.12065 -0.2794)
			(end -0.12065 -0.2794)
			(stroke
				(width 0.1)
				(type default)
			)
			(layer "B.Fab")
		)
		(fp_line
			(start -0.67945 -0.3048)
			(end -0.67945 0.3048)
			(stroke
				(width 0.1)
				(type default)
			)
			(layer "B.Fab")
		)
		(fp_line
			(start -0.12065 -0.3048)
			(end -0.67945 -0.3048)
			(stroke
				(width 0.1)
				(type default)
			)
			(layer "B.Fab")
		)
		(fp_line
			(start 0.12065 -0.305054)
			(end 0.12065 -0.2794)
			(stroke
				(width 0.1)
				(type default)
			)
			(layer "B.Fab")
		)
		(fp_line
			(start 0.67945 -0.305054)
			(end 0.12065 -0.305054)
			(stroke
				(width 0.1)
				(type default)
			)
			(layer "B.Fab")
		)
		(pad "1" smd circle
			(at 0.40005 0 90)
			(size 0 0)
			(layers "B.Cu" "B.Mask" "B.Paste")
			(net "SMB_PMBUS_3V3AUX_SCL")
		)
		(pad "2" smd circle
			(at -0.40005 0 90)
			(size 0 0)
			(layers "B.Cu" "B.Mask" "B.Paste")
			(net "P3V3_AUX")
		)
	)
	(footprint ""
		(layer "B.Cu")
		(at 370.905278 -147.568158)
		(property "Reference" "PR283"
			(at 0 0 0)
			(layer "B.SilkS")
			(hide yes)
			(effects
				(font
					(size 1.27 1.27)
				)
				(justify mirror)
			)
		)
		(property "Value" ""
			(at 0 0 0)
			(layer "B.Fab")
			(effects
				(font
					(size 1.27 1.27)
				)
				(justify mirror)
			)
		)
		(duplicate_pad_numbers_are_jumpers no)
		(fp_line
			(start -0.7874 -0.4064)
			(end -0.7874 0.4064)
			(stroke
				(width 0.1524)
				(type default)
			)
			(layer "B.SilkS")
		)
		(fp_line
			(start -0.7874 0.4064)
			(end 0.7874 0.4064)
			(stroke
				(width 0.1524)
				(type default)
			)
			(layer "B.SilkS")
		)
		(fp_line
			(start 0.7874 -0.4064)
			(end -0.7874 -0.4064)
			(stroke
				(width 0.1524)
				(type default)
			)
			(layer "B.SilkS")
		)
		(fp_line
			(start 0.7874 0.4064)
			(end 0.7874 -0.4064)
			(stroke
				(width 0.1524)
				(type default)
			)
			(layer "B.SilkS")
		)
		(fp_line
			(start -0.67945 -0.3048)
			(end -0.67945 0.3048)
			(stroke
				(width 0.1)
				(type default)
			)
			(layer "B.Fab")
		)
		(fp_line
			(start -0.67945 0.3048)
			(end -0.120396 0.3048)
			(stroke
				(width 0.1)
				(type default)
			)
			(layer "B.Fab")
		)
		(fp_line
			(start -0.12065 -0.3048)
			(end -0.67945 -0.3048)
			(stroke
				(width 0.1)
				(type default)
			)
			(layer "B.Fab")
		)
		(fp_line
			(start -0.12065 -0.2794)
			(end -0.12065 -0.3048)
			(stroke
				(width 0.1)
				(type default)
			)
			(layer "B.Fab")
		)
		(fp_line
			(start -0.120396 0.2794)
			(end 0.12065 0.2794)
			(stroke
				(width 0.1)
				(type default)
			)
			(layer "B.Fab")
		)
		(fp_line
			(start -0.120396 0.3048)
			(end -0.120396 0.2794)
			(stroke
				(width 0.1)
				(type default)
			)
			(layer "B.Fab")
		)
		(fp_line
			(start 0.12065 -0.305054)
			(end 0.12065 -0.2794)
			(stroke
				(width 0.1)
				(type default)
			)
			(layer "B.Fab")
		)
		(fp_line
			(start 0.12065 -0.2794)
			(end -0.12065 -0.2794)
			(stroke
				(width 0.1)
				(type default)
			)
			(layer "B.Fab")
		)
		(fp_line
			(start 0.12065 0.2794)
			(end 0.12065 0.3048)
			(stroke
				(width 0.1)
				(type default)
			)
			(layer "B.Fab")
		)
		(fp_line
			(start 0.12065 0.3048)
			(end 0.67945 0.3048)
			(stroke
				(width 0.1)
				(type default)
			)
			(layer "B.Fab")
		)
		(fp_line
			(start 0.67945 -0.305054)
			(end 0.12065 -0.305054)
			(stroke
				(width 0.1)
				(type default)
			)
			(layer "B.Fab")
		)
		(fp_line
			(start 0.67945 0.3048)
			(end 0.67945 -0.305054)
			(stroke
				(width 0.1)
				(type default)
			)
			(layer "B.Fab")
		)
		(pad "1" smd circle
			(at 0.40005 0 180)
			(size 0 0)
			(layers "B.Cu" "B.Mask" "B.Paste")
			(net "SVID_PVDDCR_CPU0_P0_SVTI")
		)
		(pad "2" smd circle
			(at -0.40005 0 180)
			(size 0 0)
			(layers "B.Cu" "B.Mask" "B.Paste")
			(net "GND")
		)
	)
	(footprint ""
		(layer "B.Cu")
		(at 164.062918 -119.336058)
		(property "Reference" "R6092"
			(at 0 0 0)
			(layer "B.SilkS")
			(hide yes)
			(effects
				(font
					(size 1.27 1.27)
				)
				(justify mirror)
			)
		)
		(property "Value" ""
			(at 0 0 0)
			(layer "B.Fab")
			(effects
				(font
					(size 1.27 1.27)
				)
				(justify mirror)
			)
		)
		(duplicate_pad_numbers_are_jumpers no)
		(fp_line
			(start -0.7874 -0.4064)
			(end -0.7874 0.4064)
			(stroke
				(width 0.1524)
				(type default)
			)
			(layer "B.SilkS")
		)
		(fp_line
			(start -0.7874 0.4064)
			(end 0.7874 0.4064)
			(stroke
				(width 0.1524)
				(type default)
			)
			(layer "B.SilkS")
		)
		(fp_line
			(start 0.7874 -0.4064)
			(end -0.7874 -0.4064)
			(stroke
				(width 0.1524)
				(type default)
			)
			(layer "B.SilkS")
		)
		(fp_line
			(start 0.7874 0.4064)
			(end 0.7874 -0.4064)
			(stroke
				(width 0.1524)
				(type default)
			)
			(layer "B.SilkS")
		)
		(fp_line
			(start -0.67945 -0.3048)
			(end -0.67945 0.3048)
			(stroke
				(width 0.1)
				(type default)
			)
			(layer "B.Fab")
		)
		(fp_line
			(start -0.67945 0.3048)
			(end -0.120396 0.3048)
			(stroke
				(width 0.1)
				(type default)
			)
			(layer "B.Fab")
		)
		(fp_line
			(start -0.12065 -0.3048)
			(end -0.67945 -0.3048)
			(stroke
				(width 0.1)
				(type default)
			)
			(layer "B.Fab")
		)
		(fp_line
			(start -0.12065 -0.2794)
			(end -0.12065 -0.3048)
			(stroke
				(width 0.1)
				(type default)
			)
			(layer "B.Fab")
		)
		(fp_line
			(start -0.120396 0.2794)
			(end 0.12065 0.2794)
			(stroke
				(width 0.1)
				(type default)
			)
			(layer "B.Fab")
		)
		(fp_line
			(start -0.120396 0.3048)
			(end -0.120396 0.2794)
			(stroke
				(width 0.1)
				(type default)
			)
			(layer "B.Fab")
		)
		(fp_line
			(start 0.12065 -0.305054)
			(end 0.12065 -0.2794)
			(stroke
				(width 0.1)
				(type default)
			)
			(layer "B.Fab")
		)
		(fp_line
			(start 0.12065 -0.2794)
			(end -0.12065 -0.2794)
			(stroke
				(width 0.1)
				(type default)
			)
			(layer "B.Fab")
		)
		(fp_line
			(start 0.12065 0.2794)
			(end 0.12065 0.3048)
			(stroke
				(width 0.1)
				(type default)
			)
			(layer "B.Fab")
		)
		(fp_line
			(start 0.12065 0.3048)
			(end 0.67945 0.3048)
			(stroke
				(width 0.1)
				(type default)
			)
			(layer "B.Fab")
		)
		(fp_line
			(start 0.67945 -0.305054)
			(end 0.12065 -0.305054)
			(stroke
				(width 0.1)
				(type default)
			)
			(layer "B.Fab")
		)
		(fp_line
			(start 0.67945 0.3048)
			(end 0.67945 -0.305054)
			(stroke
				(width 0.1)
				(type default)
			)
			(layer "B.Fab")
		)
		(pad "1" smd circle
			(at 0.40005 0 180)
			(size 0 0)
			(layers "B.Cu" "B.Mask" "B.Paste")
			(net "SCM_SYS_PWROK_R")
		)
		(pad "2" smd circle
			(at -0.40005 0 180)
			(size 0 0)
			(layers "B.Cu" "B.Mask" "B.Paste")
			(net "SCM_SYS_PWROK_R1")
		)
	)
	(footprint ""
		(layer "B.Cu")
		(at 454.188068 -192.660016)
		(property "Reference" "C170"
			(at 0 0 0)
			(layer "B.SilkS")
			(hide yes)
			(effects
				(font
					(size 1.27 1.27)
				)
				(justify mirror)
			)
		)
		(property "Value" ""
			(at 0 0 0)
			(layer "B.Fab")
			(effects
				(font
					(size 1.27 1.27)
				)
				(justify mirror)
			)
		)
		(duplicate_pad_numbers_are_jumpers no)
		(fp_line
			(start -1.524 -0.762)
			(end -1.524 0.762)
			(stroke
				(width 0.1524)
				(type default)
			)
			(layer "B.SilkS")
		)
		(fp_line
			(start -1.524 0.762)
			(end 1.524 0.762)
			(stroke
				(width 0.1524)
				(type default)
			)
			(layer "B.SilkS")
		)
		(fp_line
			(start 1.524 -0.762)
			(end -1.524 -0.762)
			(stroke
				(width 0.1524)
				(type default)
			)
			(layer "B.SilkS")
		)
		(fp_line
			(start 1.524 0.762)
			(end 1.524 -0.762)
			(stroke
				(width 0.1524)
				(type default)
			)
			(layer "B.SilkS")
		)
		(fp_line
			(start -1.1049 -0.724916)
			(end 1.1049 -0.724916)
			(stroke
				(width 0.1)
				(type default)
			)
			(layer "B.Fab")
		)
		(fp_line
			(start -1.1049 0.724916)
			(end -1.1049 -0.724916)
			(stroke
				(width 0.1)
				(type default)
			)
			(layer "B.Fab")
		)
		(fp_line
			(start 1.1049 -0.724916)
			(end 1.1049 0.724916)
			(stroke
				(width 0.1)
				(type default)
			)
			(layer "B.Fab")
		)
		(fp_line
			(start 1.1049 0.724916)
			(end -1.1049 0.724916)
			(stroke
				(width 0.1)
				(type default)
			)
			(layer "B.Fab")
		)
		(pad "1" smd rect
			(at 0.889 0)
			(size 1.016 1.27)
			(layers "B.Cu" "B.Mask" "B.Paste")
			(net "P12V_MEM_CPU0")
		)
		(pad "2" smd rect
			(at -0.889 0)
			(size 1.016 1.27)
			(layers "B.Cu" "B.Mask" "B.Paste")
			(net "GND")
		)
	)
)
